# SCM (Grand Teton) — schematic netlist excerpt (pin names and nets, part order shuffled) for the footprints in the layout excerpt that follows; sources: Cadence DE-HDL packaged netlist, KiCad conversion of 12092022_DA0F0TMDCD0_F0T_Management_Board_D_brd_V3_OCP.brd

R263  Q_RES  33.2 1% CHIP  pkg 0402LF  page 35 : A = RST_MB_STBY_N ; B = RST_MB_STBY_R_N
R367  Q_RES  120 1% CHIP  pkg 0402LF  page 20 : A = M_BMC_DDR4_MRAS_N ; B = P1V2_AUX

(kicad_pcb
	(version 20260206)
	(generator "pcbnew")
	(generator_version "10.0")
	(general
		(thickness 1.6)
		(legacy_teardrops no)
	)
	(paper "A4")
	(title_block
		(title "12092022_DA0F0TMDCD0_F0T_Management_Board_D_brd_V3_OCP.brd")
		(comment 1 "Grand Teton / footprints 1426-1427 of 1440")
	)
	(layers
		(0 "F.Cu" signal "TOP")
		(4 "In1.Cu" signal "GND")
		(6 "In2.Cu" signal "IN1")
		(8 "In3.Cu" signal "GND1")
		(10 "In4.Cu" signal "IN2")
		(12 "In5.Cu" signal "VCC")
		(14 "In6.Cu" signal "VCC1")
		(16 "In7.Cu" signal "IN3")
		(18 "In8.Cu" signal "GND2")
		(20 "In9.Cu" signal "IN4")
		(22 "In10.Cu" signal "GND3")
		(2 "B.Cu" signal "BOTTOM")
		(9 "F.Adhes" user "F.Adhesive")
		(11 "B.Adhes" user "B.Adhesive")
		(13 "F.Paste" user "Package Geometry/Pastemask Top")
		(15 "B.Paste" user "Package Geometry/Pastemask Bottom")
		(5 "F.SilkS" user "Ref Des/Silkscreen Top")
		(7 "B.SilkS" user "Ref Des/Silkscreen Bottom")
		(1 "F.Mask" user "Board Geometry/Soldermask Top")
		(3 "B.Mask" user "Board Geometry/Soldermask Bottom")
		(17 "Dwgs.User" user "User.Drawings")
		(19 "Cmts.User" user "User.Comments")
		(21 "Eco1.User" user "User.Eco1")
		(23 "Eco2.User" user "User.Eco2")
		(25 "Edge.Cuts" user "Board Geometry/Outline")
		(27 "Margin" user)
		(31 "F.CrtYd" user "Package Geometry/Place Bound Top")
		(29 "B.CrtYd" user "Package Geometry/Place Bound Bottom")
		(35 "F.Fab" user "Ref Des/Assembly Top")
		(33 "B.Fab" user "Ref Des/Assembly Bottom")
	)
	(footprint ""
		(layer "B.Cu")
		(at 81.686908 -47.98568 -90)
		(property "Reference" "R367"
			(at 0 0 90)
			(layer "B.SilkS")
			(hide yes)
			(effects
				(font
					(size 1.27 1.27)
				)
				(justify mirror)
			)
		)
		(property "Value" ""
			(at 0 0 90)
			(layer "B.Fab")
			(effects
				(font
					(size 1.27 1.27)
				)
				(justify mirror)
			)
		)
		(duplicate_pad_numbers_are_jumpers no)
		(fp_line
			(start -0.7874 0.4064)
			(end 0.7874 0.4064)
			(stroke
				(width 0.1524)
				(type default)
			)
			(layer "B.SilkS")
		)
		(fp_line
			(start 0.7874 0.4064)
			(end 0.7874 -0.4064)
			(stroke
				(width 0.1524)
				(type default)
			)
			(layer "B.SilkS")
		)
		(fp_line
			(start -0.7874 -0.4064)
			(end -0.7874 0.4064)
			(stroke
				(width 0.1524)
				(type default)
			)
			(layer "B.SilkS")
		)
		(fp_line
			(start 0.7874 -0.4064)
			(end -0.7874 -0.4064)
			(stroke
				(width 0.1524)
				(type default)
			)
			(layer "B.SilkS")
		)
		(fp_line
			(start -0.67945 0.3048)
			(end -0.120396 0.3048)
			(stroke
				(width 0.1)
				(type default)
			)
			(layer "B.Fab")
		)
		(fp_line
			(start -0.120396 0.3048)
			(end -0.120396 0.2794)
			(stroke
				(width 0.1)
				(type default)
			)
			(layer "B.Fab")
		)
		(fp_line
			(start 0.12065 0.3048)
			(end 0.67945 0.3048)
			(stroke
				(width 0.1)
				(type default)
			)
			(layer "B.Fab")
		)
		(fp_line
			(start 0.67945 0.3048)
			(end 0.67945 -0.305054)
			(stroke
				(width 0.1)
				(type default)
			)
			(layer "B.Fab")
		)
		(fp_line
			(start -0.120396 0.2794)
			(end 0.12065 0.2794)
			(stroke
				(width 0.1)
				(type default)
			)
			(layer "B.Fab")
		)
		(fp_line
			(start 0.12065 0.2794)
			(end 0.12065 0.3048)
			(stroke
				(width 0.1)
				(type default)
			)
			(layer "B.Fab")
		)
		(fp_line
			(start -0.12065 -0.2794)
			(end -0.12065 -0.3048)
			(stroke
				(width 0.1)
				(type default)
			)
			(layer "B.Fab")
		)
		(fp_line
			(start 0.12065 -0.2794)
			(end -0.12065 -0.2794)
			(stroke
				(width 0.1)
				(type default)
			)
			(layer "B.Fab")
		)
		(fp_line
			(start -0.67945 -0.3048)
			(end -0.67945 0.3048)
			(stroke
				(width 0.1)
				(type default)
			)
			(layer "B.Fab")
		)
		(fp_line
			(start -0.12065 -0.3048)
			(end -0.67945 -0.3048)
			(stroke
				(width 0.1)
				(type default)
			)
			(layer "B.Fab")
		)
		(fp_line
			(start 0.12065 -0.305054)
			(end 0.12065 -0.2794)
			(stroke
				(width 0.1)
				(type default)
			)
			(layer "B.Fab")
		)
		(fp_line
			(start 0.67945 -0.305054)
			(end 0.12065 -0.305054)
			(stroke
				(width 0.1)
				(type default)
			)
			(layer "B.Fab")
		)
		(pad "1" smd circle
			(at 0.40005 0 90)
			(size 0 0)
			(layers "B.Cu" "B.Mask" "B.Paste")
			(net "M_BMC_DDR4_MRAS_N")
		)
		(pad "2" smd circle
			(at -0.40005 0 90)
			(size 0 0)
			(layers "B.Cu" "B.Mask" "B.Paste")
			(net "P1V2_AUX")
		)
	)
	(footprint ""
		(layer "B.Cu")
		(at 14.859 -93.3958 180)
		(property "Reference" "R263"
			(at 0 0 0)
			(layer "B.SilkS")
			(hide yes)
			(effects
				(font
					(size 1.27 1.27)
				)
				(justify mirror)
			)
		)
		(property "Value" ""
			(at 0 0 0)
			(layer "B.Fab")
			(effects
				(font
					(size 1.27 1.27)
				)
				(justify mirror)
			)
		)
		(duplicate_pad_numbers_are_jumpers no)
		(fp_line
			(start 0.7874 0.4064)
			(end 0.7874 -0.4064)
			(stroke
				(width 0.1524)
				(type default)
			)
			(layer "B.SilkS")
		)
		(fp_line
			(start 0.7874 -0.4064)
			(end -0.7874 -0.4064)
			(stroke
				(width 0.1524)
				(type default)
			)
			(layer "B.SilkS")
		)
		(fp_line
			(start -0.7874 0.4064)
			(end 0.7874 0.4064)
			(stroke
				(width 0.1524)
				(type default)
			)
			(layer "B.SilkS")
		)
		(fp_line
			(start -0.7874 -0.4064)
			(end -0.7874 0.4064)
			(stroke
				(width 0.1524)
				(type default)
			)
			(layer "B.SilkS")
		)
		(fp_line
			(start 0.67945 0.3048)
			(end 0.67945 -0.305054)
			(stroke
				(width 0.1)
				(type default)
			)
			(layer "B.Fab")
		)
		(fp_line
			(start 0.67945 -0.305054)
			(end 0.12065 -0.305054)
			(stroke
				(width 0.1)
				(type default)
			)
			(layer "B.Fab")
		)
		(fp_line
			(start 0.12065 0.3048)
			(end 0.67945 0.3048)
			(stroke
				(width 0.1)
				(type default)
			)
			(layer "B.Fab")
		)
		(fp_line
			(start 0.12065 0.2794)
			(end 0.12065 0.3048)
			(stroke
				(width 0.1)
				(type default)
			)
			(layer "B.Fab")
		)
		(fp_line
			(start 0.12065 -0.2794)
			(end -0.12065 -0.2794)
			(stroke
				(width 0.1)
				(type default)
			)
			(layer "B.Fab")
		)
		(fp_line
			(start 0.12065 -0.305054)
			(end 0.12065 -0.2794)
			(stroke
				(width 0.1)
				(type default)
			)
			(layer "B.Fab")
		)
		(fp_line
			(start -0.120396 0.3048)
			(end -0.120396 0.2794)
			(stroke
				(width 0.1)
				(type default)
			)
			(layer "B.Fab")
		)
		(fp_line
			(start -0.120396 0.2794)
			(end 0.12065 0.2794)
			(stroke
				(width 0.1)
				(type default)
			)
			(layer "B.Fab")
		)
		(fp_line
			(start -0.12065 -0.2794)
			(end -0.12065 -0.3048)
			(stroke
				(width 0.1)
				(type default)
			)
			(layer "B.Fab")
		)
		(fp_line
			(start -0.12065 -0.3048)
			(end -0.67945 -0.3048)
			(stroke
				(width 0.1)
				(type default)
			)
			(layer "B.Fab")
		)
		(fp_line
			(start -0.67945 0.3048)
			(end -0.120396 0.3048)
			(stroke
				(width 0.1)
				(type default)
			)
			(layer "B.Fab")
		)
		(fp_line
			(start -0.67945 -0.3048)
			(end -0.67945 0.3048)
			(stroke
				(width 0.1)
				(type default)
			)
			(layer "B.Fab")
		)
		(pad "1" smd circle
			(at 0.40005 0)
			(size 0 0)
			(layers "B.Cu" "B.Mask" "B.Paste")
			(net "RST_MB_STBY_N")
		)
		(pad "2" smd circle
			(at -0.40005 0)
			(size 0 0)
			(layers "B.Cu" "B.Mask" "B.Paste")
			(net "RST_MB_STBY_R_N")
		)
	)
)
